(kicad_pcb
	(version 20260206)
	(generator "pcbnew")
	(generator_version "10.0")
	(general
		(thickness 1.6)
		(legacy_teardrops no)
	)
	(paper "A4")
	(title_block
		(title "01162023_DA0F0TEBIF0_F0T_Expander_BD_F_brd_V02_OCP.brd")
		(comment 1 "Grand Teton / footprints 7464-7474 of 9728")
	)
	(layers
		(0 "F.Cu" signal "TOP")
		(4 "In1.Cu" signal "GND")
		(6 "In2.Cu" signal "VCC")
		(8 "In3.Cu" signal "VCC1")
		(10 "In4.Cu" signal "GND1")
		(12 "In5.Cu" signal "IN1")
		(14 "In6.Cu" signal "GND2")
		(16 "In7.Cu" signal "IN2")
		(18 "In8.Cu" signal "GND3")
		(20 "In9.Cu" signal "IN3")
		(22 "In10.Cu" signal "GND4")
		(24 "In11.Cu" signal "IN4")
		(26 "In12.Cu" signal "GND5")
		(28 "In13.Cu" signal "IN5")
		(30 "In14.Cu" signal "GND6")
		(32 "In15.Cu" signal "IN6")
		(34 "In16.Cu" signal "GND7")
		(2 "B.Cu" signal "BOTTOM")
		(9 "F.Adhes" user "F.Adhesive")
		(11 "B.Adhes" user "B.Adhesive")
		(13 "F.Paste" user "Package Geometry/Pastemask Top")
		(15 "B.Paste" user "Package Geometry/Pastemask Bottom")
		(5 "F.SilkS" user "Ref Des/Silkscreen Top")
		(7 "B.SilkS" user "Ref Des/Silkscreen Bottom")
		(1 "F.Mask" user "Board Geometry/Soldermask Top")
		(3 "B.Mask" user "Board Geometry/Soldermask Bottom")
		(17 "Dwgs.User" user "User.Drawings")
		(19 "Cmts.User" user "User.Comments")
		(21 "Eco1.User" user "User.Eco1")
		(23 "Eco2.User" user "User.Eco2")
		(25 "Edge.Cuts" user "Board Geometry/Outline")
		(27 "Margin" user)
		(31 "F.CrtYd" user "Package Geometry/Place Bound Top")
		(29 "B.CrtYd" user "Package Geometry/Place Bound Bottom")
		(35 "F.Fab" user "Ref Des/Assembly Top")
		(33 "B.Fab" user "Ref Des/Assembly Bottom")
	)
	(footprint ""
		(layer "B.Cu")
		(at 299.449744 -290.199826 90)
		(property "Reference" "C1705"
			(at 0 0 90)
			(layer "B.SilkS")
			(hide yes)
			(effects
				(font
					(size 1.27 1.27)
				)
				(justify mirror)
			)
		)
		(property "Value" ""
			(at 0 0 90)
			(layer "B.Fab")
			(effects
				(font
					(size 1.27 1.27)
				)
				(justify mirror)
			)
		)
		(duplicate_pad_numbers_are_jumpers no)
		(fp_line
			(start 0.299974 -0.150114)
			(end -0.299974 -0.150114)
			(stroke
				(width 0.1)
				(type default)
			)
			(layer "B.Fab")
		)
		(fp_line
			(start -0.299974 -0.150114)
			(end -0.299974 0.150114)
			(stroke
				(width 0.1)
				(type default)
			)
			(layer "B.Fab")
		)
		(fp_line
			(start 0.299974 0.150114)
			(end 0.299974 -0.150114)
			(stroke
				(width 0.1)
				(type default)
			)
			(layer "B.Fab")
		)
		(fp_line
			(start -0.299974 0.150114)
			(end 0.299974 0.150114)
			(stroke
				(width 0.1)
				(type default)
			)
			(layer "B.Fab")
		)
		(pad "1" smd rect
			(at 0.2667 0 270)
			(size 0.3048 0.381)
			(layers "B.Cu" "B.Mask" "B.Paste")
			(net "P0V8_SERDES_VDDA_PEX2")
		)
		(pad "2" smd rect
			(at -0.2667 0 270)
			(size 0.3048 0.381)
			(layers "B.Cu" "B.Mask" "B.Paste")
			(net "GND")
		)
	)
	(footprint ""
		(layer "B.Cu")
		(at 342.175846 -293.506906 90)
		(property "Reference" "PC148"
			(at 0 0 90)
			(layer "B.SilkS")
			(hide yes)
			(effects
				(font
					(size 1.27 1.27)
				)
				(justify mirror)
			)
		)
		(property "Value" ""
			(at 0 0 90)
			(layer "B.Fab")
			(effects
				(font
					(size 1.27 1.27)
				)
				(justify mirror)
			)
		)
		(duplicate_pad_numbers_are_jumpers no)
		(fp_line
			(start 1.524 -0.762)
			(end -1.524 -0.762)
			(stroke
				(width 0.1524)
				(type default)
			)
			(layer "B.SilkS")
		)
		(fp_line
			(start -1.524 -0.762)
			(end -1.524 0.762)
			(stroke
				(width 0.1524)
				(type default)
			)
			(layer "B.SilkS")
		)
		(fp_line
			(start 1.524 0.762)
			(end 1.524 -0.762)
			(stroke
				(width 0.1524)
				(type default)
			)
			(layer "B.SilkS")
		)
		(fp_line
			(start -1.524 0.762)
			(end 1.524 0.762)
			(stroke
				(width 0.1524)
				(type default)
			)
			(layer "B.SilkS")
		)
		(fp_line
			(start 1.1049 -0.724916)
			(end 1.1049 0.724916)
			(stroke
				(width 0.1)
				(type default)
			)
			(layer "B.Fab")
		)
		(fp_line
			(start -1.1049 -0.724916)
			(end 1.1049 -0.724916)
			(stroke
				(width 0.1)
				(type default)
			)
			(layer "B.Fab")
		)
		(fp_line
			(start 1.1049 0.724916)
			(end -1.1049 0.724916)
			(stroke
				(width 0.1)
				(type default)
			)
			(layer "B.Fab")
		)
		(fp_line
			(start -1.1049 0.724916)
			(end -1.1049 -0.724916)
			(stroke
				(width 0.1)
				(type default)
			)
			(layer "B.Fab")
		)
		(pad "1" smd rect
			(at 0.889 0 90)
			(size 1.016 1.27)
			(layers "B.Cu" "B.Mask" "B.Paste")
			(net "P0V8_PEX2")
		)
		(pad "2" smd rect
			(at -0.889 0 90)
			(size 1.016 1.27)
			(layers "B.Cu" "B.Mask" "B.Paste")
			(net "GND")
		)
	)
	(footprint ""
		(layer "B.Cu")
		(at 165.299898 -291.624766)
		(property "Reference" "C1360"
			(at 0 0 0)
			(layer "B.SilkS")
			(hide yes)
			(effects
				(font
					(size 1.27 1.27)
				)
				(justify mirror)
			)
		)
		(property "Value" ""
			(at 0 0 0)
			(layer "B.Fab")
			(effects
				(font
					(size 1.27 1.27)
				)
				(justify mirror)
			)
		)
		(duplicate_pad_numbers_are_jumpers no)
		(fp_line
			(start -0.299974 -0.150114)
			(end -0.299974 0.150114)
			(stroke
				(width 0.1)
				(type default)
			)
			(layer "B.Fab")
		)
		(fp_line
			(start -0.299974 0.150114)
			(end 0.299974 0.150114)
			(stroke
				(width 0.1)
				(type default)
			)
			(layer "B.Fab")
		)
		(fp_line
			(start 0.299974 -0.150114)
			(end -0.299974 -0.150114)
			(stroke
				(width 0.1)
				(type default)
			)
			(layer "B.Fab")
		)
		(fp_line
			(start 0.299974 0.150114)
			(end 0.299974 -0.150114)
			(stroke
				(width 0.1)
				(type default)
			)
			(layer "B.Fab")
		)
		(pad "1" smd rect
			(at 0.2667 0 180)
			(size 0.3048 0.381)
			(layers "B.Cu" "B.Mask" "B.Paste")
			(net "P0V8_PEX1")
		)
		(pad "2" smd rect
			(at -0.2667 0 180)
			(size 0.3048 0.381)
			(layers "B.Cu" "B.Mask" "B.Paste")
			(net "GND")
		)
	)
	(footprint ""
		(layer "B.Cu")
		(at 165.655244 -156.0576)
		(property "Reference" "R130"
			(at 0 0 0)
			(layer "B.SilkS")
			(hide yes)
			(effects
				(font
					(size 1.27 1.27)
				)
				(justify mirror)
			)
		)
		(property "Value" ""
			(at 0 0 0)
			(layer "B.Fab")
			(effects
				(font
					(size 1.27 1.27)
				)
				(justify mirror)
			)
		)
		(duplicate_pad_numbers_are_jumpers no)
		(fp_line
			(start -0.7874 -0.4064)
			(end -0.7874 0.4064)
			(stroke
				(width 0.1524)
				(type default)
			)
			(layer "B.SilkS")
		)
		(fp_line
			(start -0.7874 0.4064)
			(end 0.7874 0.4064)
			(stroke
				(width 0.1524)
				(type default)
			)
			(layer "B.SilkS")
		)
		(fp_line
			(start 0.7874 -0.4064)
			(end -0.7874 -0.4064)
			(stroke
				(width 0.1524)
				(type default)
			)
			(layer "B.SilkS")
		)
		(fp_line
			(start 0.7874 0.4064)
			(end 0.7874 -0.4064)
			(stroke
				(width 0.1524)
				(type default)
			)
			(layer "B.SilkS")
		)
		(fp_line
			(start -0.67945 -0.3048)
			(end -0.67945 0.3048)
			(stroke
				(width 0.1)
				(type default)
			)
			(layer "B.Fab")
		)
		(fp_line
			(start -0.67945 0.3048)
			(end -0.120396 0.3048)
			(stroke
				(width 0.1)
				(type default)
			)
			(layer "B.Fab")
		)
		(fp_line
			(start -0.12065 -0.3048)
			(end -0.67945 -0.3048)
			(stroke
				(width 0.1)
				(type default)
			)
			(layer "B.Fab")
		)
		(fp_line
			(start -0.12065 -0.2794)
			(end -0.12065 -0.3048)
			(stroke
				(width 0.1)
				(type default)
			)
			(layer "B.Fab")
		)
		(fp_line
			(start -0.120396 0.2794)
			(end 0.12065 0.2794)
			(stroke
				(width 0.1)
				(type default)
			)
			(layer "B.Fab")
		)
		(fp_line
			(start -0.120396 0.3048)
			(end -0.120396 0.2794)
			(stroke
				(width 0.1)
				(type default)
			)
			(layer "B.Fab")
		)
		(fp_line
			(start 0.12065 -0.305054)
			(end 0.12065 -0.2794)
			(stroke
				(width 0.1)
				(type default)
			)
			(layer "B.Fab")
		)
		(fp_line
			(start 0.12065 -0.2794)
			(end -0.12065 -0.2794)
			(stroke
				(width 0.1)
				(type default)
			)
			(layer "B.Fab")
		)
		(fp_line
			(start 0.12065 0.2794)
			(end 0.12065 0.3048)
			(stroke
				(width 0.1)
				(type default)
			)
			(layer "B.Fab")
		)
		(fp_line
			(start 0.12065 0.3048)
			(end 0.67945 0.3048)
			(stroke
				(width 0.1)
				(type default)
			)
			(layer "B.Fab")
		)
		(fp_line
			(start 0.67945 -0.305054)
			(end 0.12065 -0.305054)
			(stroke
				(width 0.1)
				(type default)
			)
			(layer "B.Fab")
		)
		(fp_line
			(start 0.67945 0.3048)
			(end 0.67945 -0.305054)
			(stroke
				(width 0.1)
				(type default)
			)
			(layer "B.Fab")
		)
		(pad "1" smd circle
			(at 0.40005 0 180)
			(size 0 0)
			(layers "B.Cu" "B.Mask" "B.Paste")
			(net "NIC2_SLOT_ID1")
		)
		(pad "2" smd circle
			(at -0.40005 0 180)
			(size 0 0)
			(layers "B.Cu" "B.Mask" "B.Paste")
			(net "GND")
		)
	)
	(footprint ""
		(layer "B.Cu")
		(at 259.448554 -81.001616 -90)
		(property "Reference" "C2635"
			(at 0 0 90)
			(layer "B.SilkS")
			(hide yes)
			(effects
				(font
					(size 1.27 1.27)
				)
				(justify mirror)
			)
		)
		(property "Value" ""
			(at 0 0 90)
			(layer "B.Fab")
			(effects
				(font
					(size 1.27 1.27)
				)
				(justify mirror)
			)
		)
		(duplicate_pad_numbers_are_jumpers no)
		(fp_line
			(start -0.7874 0.4064)
			(end 0.7874 0.4064)
			(stroke
				(width 0.1524)
				(type default)
			)
			(layer "B.SilkS")
		)
		(fp_line
			(start 0.7874 0.4064)
			(end 0.7874 -0.4064)
			(stroke
				(width 0.1524)
				(type default)
			)
			(layer "B.SilkS")
		)
		(fp_line
			(start -0.7874 -0.4064)
			(end -0.7874 0.4064)
			(stroke
				(width 0.1524)
				(type default)
			)
			(layer "B.SilkS")
		)
		(fp_line
			(start 0.7874 -0.4064)
			(end -0.7874 -0.4064)
			(stroke
				(width 0.1524)
				(type default)
			)
			(layer "B.SilkS")
		)
		(fp_line
			(start -0.67945 0.3048)
			(end -0.120396 0.3048)
			(stroke
				(width 0.1)
				(type default)
			)
			(layer "B.Fab")
		)
		(fp_line
			(start -0.120396 0.3048)
			(end -0.120396 0.2794)
			(stroke
				(width 0.1)
				(type default)
			)
			(layer "B.Fab")
		)
		(fp_line
			(start 0.12065 0.3048)
			(end 0.67945 0.3048)
			(stroke
				(width 0.1)
				(type default)
			)
			(layer "B.Fab")
		)
		(fp_line
			(start 0.67945 0.3048)
			(end 0.67945 -0.305054)
			(stroke
				(width 0.1)
				(type default)
			)
			(layer "B.Fab")
		)
		(fp_line
			(start -0.120396 0.2794)
			(end 0.12065 0.2794)
			(stroke
				(width 0.1)
				(type default)
			)
			(layer "B.Fab")
		)
		(fp_line
			(start 0.12065 0.2794)
			(end 0.12065 0.3048)
			(stroke
				(width 0.1)
				(type default)
			)
			(layer "B.Fab")
		)
		(fp_line
			(start -0.12065 -0.2794)
			(end -0.12065 -0.3048)
			(stroke
				(width 0.1)
				(type default)
			)
			(layer "B.Fab")
		)
		(fp_line
			(start 0.12065 -0.2794)
			(end -0.12065 -0.2794)
			(stroke
				(width 0.1)
				(type default)
			)
			(layer "B.Fab")
		)
		(fp_line
			(start -0.67945 -0.3048)
			(end -0.67945 0.3048)
			(stroke
				(width 0.1)
				(type default)
			)
			(layer "B.Fab")
		)
		(fp_line
			(start -0.12065 -0.3048)
			(end -0.67945 -0.3048)
			(stroke
				(width 0.1)
				(type default)
			)
			(layer "B.Fab")
		)
		(fp_line
			(start 0.12065 -0.305054)
			(end 0.12065 -0.2794)
			(stroke
				(width 0.1)
				(type default)
			)
			(layer "B.Fab")
		)
		(fp_line
			(start 0.67945 -0.305054)
			(end 0.12065 -0.305054)
			(stroke
				(width 0.1)
				(type default)
			)
			(layer "B.Fab")
		)
		(pad "1" smd circle
			(at 0.40005 0 90)
			(size 0 0)
			(layers "B.Cu" "B.Mask" "B.Paste")
			(net "P3V3_CLK_GEN_VDDA100M_CK440")
		)
		(pad "2" smd circle
			(at -0.40005 0 90)
			(size 0 0)
			(layers "B.Cu" "B.Mask" "B.Paste")
			(net "GND")
		)
	)
	(footprint ""
		(layer "B.Cu")
		(at 289.47491 -293.99992 -90)
		(property "Reference" "C1653"
			(at 0 0 90)
			(layer "B.SilkS")
			(hide yes)
			(effects
				(font
					(size 1.27 1.27)
				)
				(justify mirror)
			)
		)
		(property "Value" ""
			(at 0 0 90)
			(layer "B.Fab")
			(effects
				(font
					(size 1.27 1.27)
				)
				(justify mirror)
			)
		)
		(duplicate_pad_numbers_are_jumpers no)
		(fp_line
			(start -0.299974 0.150114)
			(end 0.299974 0.150114)
			(stroke
				(width 0.1)
				(type default)
			)
			(layer "B.Fab")
		)
		(fp_line
			(start 0.299974 0.150114)
			(end 0.299974 -0.150114)
			(stroke
				(width 0.1)
				(type default)
			)
			(layer "B.Fab")
		)
		(fp_line
			(start -0.299974 -0.150114)
			(end -0.299974 0.150114)
			(stroke
				(width 0.1)
				(type default)
			)
			(layer "B.Fab")
		)
		(fp_line
			(start 0.299974 -0.150114)
			(end -0.299974 -0.150114)
			(stroke
				(width 0.1)
				(type default)
			)
			(layer "B.Fab")
		)
		(pad "1" smd rect
			(at 0.2667 0 90)
			(size 0.3048 0.381)
			(layers "B.Cu" "B.Mask" "B.Paste")
			(net "P0V8_PEX2")
		)
		(pad "2" smd rect
			(at -0.2667 0 90)
			(size 0.3048 0.381)
			(layers "B.Cu" "B.Mask" "B.Paste")
			(net "GND")
		)
	)
	(footprint ""
		(layer "B.Cu")
		(at 414.124902 -286.399732 90)
		(property "Reference" "C3507"
			(at 0 0 90)
			(layer "B.SilkS")
			(hide yes)
			(effects
				(font
					(size 1.27 1.27)
				)
				(justify mirror)
			)
		)
		(property "Value" ""
			(at 0 0 90)
			(layer "B.Fab")
			(effects
				(font
					(size 1.27 1.27)
				)
				(justify mirror)
			)
		)
		(duplicate_pad_numbers_are_jumpers no)
		(fp_line
			(start 0.299974 -0.150114)
			(end -0.299974 -0.150114)
			(stroke
				(width 0.1)
				(type default)
			)
			(layer "B.Fab")
		)
		(fp_line
			(start -0.299974 -0.150114)
			(end -0.299974 0.150114)
			(stroke
				(width 0.1)
				(type default)
			)
			(layer "B.Fab")
		)
		(fp_line
			(start 0.299974 0.150114)
			(end 0.299974 -0.150114)
			(stroke
				(width 0.1)
				(type default)
			)
			(layer "B.Fab")
		)
		(fp_line
			(start -0.299974 0.150114)
			(end 0.299974 0.150114)
			(stroke
				(width 0.1)
				(type default)
			)
			(layer "B.Fab")
		)
		(pad "1" smd rect
			(at 0.2667 0 270)
			(size 0.3048 0.381)
			(layers "B.Cu" "B.Mask" "B.Paste")
			(net "P1V25_SERDES_VDDPLL_PEX3")
		)
		(pad "2" smd rect
			(at -0.2667 0 270)
			(size 0.3048 0.381)
			(layers "B.Cu" "B.Mask" "B.Paste")
			(net "GND")
		)
	)
	(footprint ""
		(layer "B.Cu")
		(at 421.249856 -297.79976 180)
		(property "Reference" "C3469"
			(at 0 0 0)
			(layer "B.SilkS")
			(hide yes)
			(effects
				(font
					(size 1.27 1.27)
				)
				(justify mirror)
			)
		)
		(property "Value" ""
			(at 0 0 0)
			(layer "B.Fab")
			(effects
				(font
					(size 1.27 1.27)
				)
				(justify mirror)
			)
		)
		(duplicate_pad_numbers_are_jumpers no)
		(fp_line
			(start 0.299974 0.150114)
			(end 0.299974 -0.150114)
			(stroke
				(width 0.1)
				(type default)
			)
			(layer "B.Fab")
		)
		(fp_line
			(start 0.299974 -0.150114)
			(end -0.299974 -0.150114)
			(stroke
				(width 0.1)
				(type default)
			)
			(layer "B.Fab")
		)
		(fp_line
			(start -0.299974 0.150114)
			(end 0.299974 0.150114)
			(stroke
				(width 0.1)
				(type default)
			)
			(layer "B.Fab")
		)
		(fp_line
			(start -0.299974 -0.150114)
			(end -0.299974 0.150114)
			(stroke
				(width 0.1)
				(type default)
			)
			(layer "B.Fab")
		)
		(pad "1" smd rect
			(at 0.2667 0)
			(size 0.3048 0.381)
			(layers "B.Cu" "B.Mask" "B.Paste")
			(net "P1V25_SERDES_VDDPLL_PEX3")
		)
		(pad "2" smd rect
			(at -0.2667 0)
			(size 0.3048 0.381)
			(layers "B.Cu" "B.Mask" "B.Paste")
			(net "GND")
		)
	)
	(footprint ""
		(layer "B.Cu")
		(at 162.4457 -301.076868)
		(property "Reference" "C3173"
			(at 0 0 0)
			(layer "B.SilkS")
			(hide yes)
			(effects
				(font
					(size 1.27 1.27)
				)
				(justify mirror)
			)
		)
		(property "Value" ""
			(at 0 0 0)
			(layer "B.Fab")
			(effects
				(font
					(size 1.27 1.27)
				)
				(justify mirror)
			)
		)
		(duplicate_pad_numbers_are_jumpers no)
		(fp_line
			(start -0.299974 -0.150114)
			(end -0.299974 0.150114)
			(stroke
				(width 0.1)
				(type default)
			)
			(layer "B.Fab")
		)
		(fp_line
			(start -0.299974 0.150114)
			(end 0.299974 0.150114)
			(stroke
				(width 0.1)
				(type default)
			)
			(layer "B.Fab")
		)
		(fp_line
			(start 0.299974 -0.150114)
			(end -0.299974 -0.150114)
			(stroke
				(width 0.1)
				(type default)
			)
			(layer "B.Fab")
		)
		(fp_line
			(start 0.299974 0.150114)
			(end 0.299974 -0.150114)
			(stroke
				(width 0.1)
				(type default)
			)
			(layer "B.Fab")
		)
		(pad "1" smd rect
			(at 0.2667 0 180)
			(size 0.3048 0.381)
			(layers "B.Cu" "B.Mask" "B.Paste")
			(net "P1V8_PEX")
		)
		(pad "2" smd rect
			(at -0.2667 0 180)
			(size 0.3048 0.381)
			(layers "B.Cu" "B.Mask" "B.Paste")
			(net "GND")
		)
	)
	(footprint ""
		(layer "B.Cu")
		(at 413.649922 -290.199826 90)
		(property "Reference" "C1958"
			(at 0 0 90)
			(layer "B.SilkS")
			(hide yes)
			(effects
				(font
					(size 1.27 1.27)
				)
				(justify mirror)
			)
		)
		(property "Value" ""
			(at 0 0 90)
			(layer "B.Fab")
			(effects
				(font
					(size 1.27 1.27)
				)
				(justify mirror)
			)
		)
		(duplicate_pad_numbers_are_jumpers no)
		(fp_line
			(start 0.299974 -0.150114)
			(end -0.299974 -0.150114)
			(stroke
				(width 0.1)
				(type default)
			)
			(layer "B.Fab")
		)
		(fp_line
			(start -0.299974 -0.150114)
			(end -0.299974 0.150114)
			(stroke
				(width 0.1)
				(type default)
			)
			(layer "B.Fab")
		)
		(fp_line
			(start 0.299974 0.150114)
			(end 0.299974 -0.150114)
			(stroke
				(width 0.1)
				(type default)
			)
			(layer "B.Fab")
		)
		(fp_line
			(start -0.299974 0.150114)
			(end 0.299974 0.150114)
			(stroke
				(width 0.1)
				(type default)
			)
			(layer "B.Fab")
		)
		(pad "1" smd rect
			(at 0.2667 0 270)
			(size 0.3048 0.381)
			(layers "B.Cu" "B.Mask" "B.Paste")
			(net "P0V8_SERDES_VDDA_PEX3")
		)
		(pad "2" smd rect
			(at -0.2667 0 270)
			(size 0.3048 0.381)
			(layers "B.Cu" "B.Mask" "B.Paste")
			(net "GND")
		)
	)
	(footprint ""
		(layer "B.Cu")
		(at 61.549788 -303.499774 -90)
		(property "Reference" "C2908"
			(at 0 0 90)
			(layer "B.SilkS")
			(hide yes)
			(effects
				(font
					(size 1.27 1.27)
				)
				(justify mirror)
			)
		)
		(property "Value" ""
			(at 0 0 90)
			(layer "B.Fab")
			(effects
				(font
					(size 1.27 1.27)
				)
				(justify mirror)
			)
		)
		(duplicate_pad_numbers_are_jumpers no)
		(fp_line
			(start -0.299974 0.150114)
			(end 0.299974 0.150114)
			(stroke
				(width 0.1)
				(type default)
			)
			(layer "B.Fab")
		)
		(fp_line
			(start 0.299974 0.150114)
			(end 0.299974 -0.150114)
			(stroke
				(width 0.1)
				(type default)
			)
			(layer "B.Fab")
		)
		(fp_line
			(start -0.299974 -0.150114)
			(end -0.299974 0.150114)
			(stroke
				(width 0.1)
				(type default)
			)
			(layer "B.Fab")
		)
		(fp_line
			(start 0.299974 -0.150114)
			(end -0.299974 -0.150114)
			(stroke
				(width 0.1)
				(type default)
			)
			(layer "B.Fab")
		)
		(pad "1" smd rect
			(at 0.2667 0 90)
			(size 0.3048 0.381)
			(layers "B.Cu" "B.Mask" "B.Paste")
			(net "P1V25_PEX0")
		)
		(pad "2" smd rect
			(at -0.2667 0 90)
			(size 0.3048 0.381)
			(layers "B.Cu" "B.Mask" "B.Paste")
			(net "GND")
		)
	)
)
